FILE_TYPE = MACRO_DRAWING;
SET COLOR_WIRE YELLOW;
SET COLOR_PROP ORANGE;
SET COLOR_DOT WHITE;
SET COLOR_ARC YELLOW;
SET COLOR_BODY GREEN;
SET COLOR_NOTE PURPLE;
SET PROP_DISPLAY VALUE;
SET PAGE_NUMBER P33;
FORCEADD GENOA_SP5..40
R 1
(-4750 3750);
FORCEPROP 1 LAST LOCATION U25
R 1
J 0
(-8406 3355);
DISPLAY 0.489362 (-8406 3355);
PAINT SKYBLUE (-8406 3355);
FORCEPROP 0 LAST $SEC 40
R 1
J 0
(-1400 4325);
DISPLAY 0.680851 (-1400 4325);
PAINT MONO (-1400 4325);
DISPLAY INVISIBLE (-1400 4325);
FORCEPROP 0 LAST CDS_SEC 40
R 1
J 0
(-1100 4225);
DISPLAY 1.021277 (-1100 4225);
DISPLAY INVISIBLE (-1100 4225);
FORCEPROP 0 LASTPIN (-2650 4300) $PN AA42
R 1
J 0
(-2660 4310);
DISPLAY 0.489362 (-2660 4310);
PAINT MONO (-2660 4310);
FORCEPROP 0 LASTPIN (-2600 4300) $PN AA72
R 1
J 0
(-2610 4310);
DISPLAY 0.489362 (-2610 4310);
PAINT MONO (-2610 4310);
FORCEPROP 0 LASTPIN (-2550 4300) $PN AD31
R 1
J 0
(-2560 4310);
DISPLAY 0.489362 (-2560 4310);
PAINT MONO (-2560 4310);
FORCEPROP 0 LASTPIN (-2500 4300) $PN AE4
R 1
J 0
(-2510 4310);
DISPLAY 0.489362 (-2510 4310);
PAINT MONO (-2510 4310);
FORCEPROP 0 LASTPIN (-2450 4300) $PN AH33
R 1
J 0
(-2460 4310);
DISPLAY 0.489362 (-2460 4310);
PAINT MONO (-2460 4310);
FORCEPROP 0 LASTPIN (-2400 4300) $PN AJ13
R 1
J 0
(-2410 4310);
DISPLAY 0.489362 (-2410 4310);
PAINT MONO (-2410 4310);
FORCEPROP 0 LASTPIN (-2350 4300) $PN AM37
R 1
J 0
(-2360 4310);
DISPLAY 0.489362 (-2360 4310);
PAINT MONO (-2360 4310);
FORCEPROP 0 LASTPIN (-2300 4300) $PN AN20
R 1
J 0
(-2310 4310);
DISPLAY 0.489362 (-2310 4310);
PAINT MONO (-2310 4310);
FORCEPROP 0 LASTPIN (-2250 4300) $PN BV42
R 1
J 0
(-2260 4310);
DISPLAY 0.489362 (-2260 4310);
PAINT MONO (-2260 4310);
FORCEPROP 0 LASTPIN (-2200 4300) $PN BW25
R 1
J 0
(-2210 4310);
DISPLAY 0.489362 (-2210 4310);
PAINT MONO (-2210 4310);
FORCEPROP 0 LASTPIN (-2150 4300) $PN CB44
R 1
J 0
(-2160 4310);
DISPLAY 0.489362 (-2160 4310);
PAINT MONO (-2160 4310);
FORCEPROP 0 LASTPIN (-2100 4300) $PN CC22
R 1
J 0
(-2110 4310);
DISPLAY 0.489362 (-2110 4310);
PAINT MONO (-2110 4310);
FORCEPROP 0 LASTPIN (-2050 4300) $PN CF46
R 1
J 0
(-2060 4310);
DISPLAY 0.489362 (-2060 4310);
PAINT MONO (-2060 4310);
FORCEPROP 0 LASTPIN (-2000 4300) $PN CG42
R 1
J 0
(-2010 4310);
DISPLAY 0.489362 (-2010 4310);
PAINT MONO (-2010 4310);
FORCEPROP 0 LASTPIN (-1950 4300) $PN CK10
R 1
J 0
(-1960 4310);
DISPLAY 0.489362 (-1960 4310);
PAINT MONO (-1960 4310);
FORCEPROP 0 LASTPIN (-1900 4300) $PN CK31
R 1
J 0
(-1910 4310);
DISPLAY 0.489362 (-1910 4310);
PAINT MONO (-1910 4310);
FORCEPROP 0 LASTPIN (-1850 4300) $PN CM50
R 1
J 0
(-1860 4310);
DISPLAY 0.489362 (-1860 4310);
PAINT MONO (-1860 4310);
FORCEPROP 0 LASTPIN (-1800 4300) $PN CN54
R 1
J 0
(-1810 4310);
DISPLAY 0.489362 (-1810 4310);
PAINT MONO (-1810 4310);
FORCEPROP 0 LASTPIN (-1750 4300) $PN CT52
R 1
J 0
(-1760 4310);
DISPLAY 0.489362 (-1760 4310);
PAINT MONO (-1760 4310);
FORCEPROP 0 LASTPIN (-1700 4300) $PN CU58
R 1
J 0
(-1710 4310);
DISPLAY 0.489362 (-1710 4310);
PAINT MONO (-1710 4310);
FORCEPROP 0 LASTPIN (-1650 4300) $PN CY57
R 1
J 0
(-1660 4310);
DISPLAY 0.489362 (-1660 4310);
PAINT MONO (-1660 4310);
FORCEPROP 0 LASTPIN (-1600 4300) $PN DA56
R 1
J 0
(-1610 4310);
DISPLAY 0.489362 (-1610 4310);
PAINT MONO (-1610 4310);
FORCEPROP 0 LASTPIN (-8000 3200) $PN DA72
R 1
J 2
(-8010 3190);
DISPLAY 0.489362 (-8010 3190);
PAINT MONO (-8010 3190);
FORCEPROP 0 LASTPIN (-7950 3200) $PN DA75
R 1
J 2
(-7960 3190);
DISPLAY 0.489362 (-7960 3190);
PAINT MONO (-7960 3190);
FORCEPROP 0 LASTPIN (-7900 3200) $PN DB3
R 1
J 2
(-7910 3190);
DISPLAY 0.489362 (-7910 3190);
PAINT MONO (-7910 3190);
FORCEPROP 0 LASTPIN (-7850 3200) $PN DB8
R 1
J 2
(-7860 3190);
DISPLAY 0.489362 (-7860 3190);
PAINT MONO (-7860 3190);
FORCEPROP 0 LASTPIN (-7800 3200) $PN DB10
R 1
J 2
(-7810 3190);
DISPLAY 0.489362 (-7810 3190);
PAINT MONO (-7810 3190);
FORCEPROP 0 LASTPIN (-7750 3200) $PN DB15
R 1
J 2
(-7760 3190);
DISPLAY 0.489362 (-7760 3190);
PAINT MONO (-7760 3190);
FORCEPROP 0 LASTPIN (-7700 3200) $PN DB17
R 1
J 2
(-7710 3190);
DISPLAY 0.489362 (-7710 3190);
PAINT MONO (-7710 3190);
FORCEPROP 0 LASTPIN (-7650 3200) $PN DB22
R 1
J 2
(-7660 3190);
DISPLAY 0.489362 (-7660 3190);
PAINT MONO (-7660 3190);
FORCEPROP 0 LASTPIN (-7600 3200) $PN DB25
R 1
J 2
(-7610 3190);
DISPLAY 0.489362 (-7610 3190);
PAINT MONO (-7610 3190);
FORCEPROP 0 LASTPIN (-7550 3200) $PN DB28
R 1
J 2
(-7560 3190);
DISPLAY 0.489362 (-7560 3190);
PAINT MONO (-7560 3190);
FORCEPROP 0 LASTPIN (-7500 3200) $PN DB31
R 1
J 2
(-7510 3190);
DISPLAY 0.489362 (-7510 3190);
PAINT MONO (-7510 3190);
FORCEPROP 0 LASTPIN (-7450 3200) $PN DB34
R 1
J 2
(-7460 3190);
DISPLAY 0.489362 (-7460 3190);
PAINT MONO (-7460 3190);
FORCEPROP 0 LASTPIN (-7400 3200) $PN DB37
R 1
J 2
(-7410 3190);
DISPLAY 0.489362 (-7410 3190);
PAINT MONO (-7410 3190);
FORCEPROP 0 LASTPIN (-7350 3200) $PN DB39
R 1
J 2
(-7360 3190);
DISPLAY 0.489362 (-7360 3190);
PAINT MONO (-7360 3190);
FORCEPROP 0 LASTPIN (-7300 3200) $PN DB42
R 1
J 2
(-7310 3190);
DISPLAY 0.489362 (-7310 3190);
PAINT MONO (-7310 3190);
FORCEPROP 0 LASTPIN (-7250 3200) $PN DB45
R 1
J 2
(-7260 3190);
DISPLAY 0.489362 (-7260 3190);
PAINT MONO (-7260 3190);
FORCEPROP 0 LASTPIN (-7200 3200) $PN DB48
R 1
J 2
(-7210 3190);
DISPLAY 0.489362 (-7210 3190);
PAINT MONO (-7210 3190);
FORCEPROP 0 LASTPIN (-7150 3200) $PN DB51
R 1
J 2
(-7160 3190);
DISPLAY 0.489362 (-7160 3190);
PAINT MONO (-7160 3190);
FORCEPROP 0 LASTPIN (-7100 3200) $PN DB54
R 1
J 2
(-7110 3190);
DISPLAY 0.489362 (-7110 3190);
PAINT MONO (-7110 3190);
FORCEPROP 0 LASTPIN (-7050 3200) $PN DB59
R 1
J 2
(-7060 3190);
DISPLAY 0.489362 (-7060 3190);
PAINT MONO (-7060 3190);
FORCEPROP 0 LASTPIN (-7000 3200) $PN DB61
R 1
J 2
(-7010 3190);
DISPLAY 0.489362 (-7010 3190);
PAINT MONO (-7010 3190);
FORCEPROP 0 LASTPIN (-6950 3200) $PN DB66
R 1
J 2
(-6960 3190);
DISPLAY 0.489362 (-6960 3190);
PAINT MONO (-6960 3190);
FORCEPROP 0 LASTPIN (-6900 3200) $PN DB68
R 1
J 2
(-6910 3190);
DISPLAY 0.489362 (-6910 3190);
PAINT MONO (-6910 3190);
FORCEPROP 0 LASTPIN (-6850 3200) $PN DB73
R 1
J 2
(-6860 3190);
DISPLAY 0.489362 (-6860 3190);
PAINT MONO (-6860 3190);
FORCEPROP 0 LASTPIN (-6800 3200) $PN DC1
R 1
J 2
(-6810 3190);
DISPLAY 0.489362 (-6810 3190);
PAINT MONO (-6810 3190);
FORCEPROP 0 LASTPIN (-6750 3200) $PN DC4
R 1
J 2
(-6760 3190);
DISPLAY 0.489362 (-6760 3190);
PAINT MONO (-6760 3190);
FORCEPROP 0 LASTPIN (-6700 3200) $PN DC6
R 1
J 2
(-6710 3190);
DISPLAY 0.489362 (-6710 3190);
PAINT MONO (-6710 3190);
FORCEPROP 0 LASTPIN (-6650 3200) $PN DC8
R 1
J 2
(-6660 3190);
DISPLAY 0.489362 (-6660 3190);
PAINT MONO (-6660 3190);
FORCEPROP 0 LASTPIN (-6600 3200) $PN DC11
R 1
J 2
(-6610 3190);
DISPLAY 0.489362 (-6610 3190);
PAINT MONO (-6610 3190);
FORCEPROP 0 LASTPIN (-6550 3200) $PN DC13
R 1
J 2
(-6560 3190);
DISPLAY 0.489362 (-6560 3190);
PAINT MONO (-6560 3190);
FORCEPROP 0 LASTPIN (-6500 3200) $PN DC15
R 1
J 2
(-6510 3190);
DISPLAY 0.489362 (-6510 3190);
PAINT MONO (-6510 3190);
FORCEPROP 0 LASTPIN (-6450 3200) $PN DC18
R 1
J 2
(-6460 3190);
DISPLAY 0.489362 (-6460 3190);
PAINT MONO (-6460 3190);
FORCEPROP 0 LASTPIN (-6400 3200) $PN DC20
R 1
J 2
(-6410 3190);
DISPLAY 0.489362 (-6410 3190);
PAINT MONO (-6410 3190);
FORCEPROP 0 LASTPIN (-6350 3200) $PN DC22
R 1
J 2
(-6360 3190);
DISPLAY 0.489362 (-6360 3190);
PAINT MONO (-6360 3190);
FORCEPROP 0 LASTPIN (-6300 3200) $PN DC25
R 1
J 2
(-6310 3190);
DISPLAY 0.489362 (-6310 3190);
PAINT MONO (-6310 3190);
FORCEPROP 0 LASTPIN (-6250 3200) $PN DC28
R 1
J 2
(-6260 3190);
DISPLAY 0.489362 (-6260 3190);
PAINT MONO (-6260 3190);
FORCEPROP 0 LASTPIN (-6200 3200) $PN DC31
R 1
J 2
(-6210 3190);
DISPLAY 0.489362 (-6210 3190);
PAINT MONO (-6210 3190);
FORCEPROP 0 LASTPIN (-6150 3200) $PN DC34
R 1
J 2
(-6160 3190);
DISPLAY 0.489362 (-6160 3190);
PAINT MONO (-6160 3190);
FORCEPROP 0 LASTPIN (-6100 3200) $PN DC42
R 1
J 2
(-6110 3190);
DISPLAY 0.489362 (-6110 3190);
PAINT MONO (-6110 3190);
FORCEPROP 0 LASTPIN (-6050 3200) $PN DC45
R 1
J 2
(-6060 3190);
DISPLAY 0.489362 (-6060 3190);
PAINT MONO (-6060 3190);
FORCEPROP 0 LASTPIN (-6000 3200) $PN DC48
R 1
J 2
(-6010 3190);
DISPLAY 0.489362 (-6010 3190);
PAINT MONO (-6010 3190);
FORCEPROP 0 LASTPIN (-5950 3200) $PN DC51
R 1
J 2
(-5960 3190);
DISPLAY 0.489362 (-5960 3190);
PAINT MONO (-5960 3190);
FORCEPROP 0 LASTPIN (-5900 3200) $PN DC54
R 1
J 2
(-5910 3190);
DISPLAY 0.489362 (-5910 3190);
PAINT MONO (-5910 3190);
FORCEPROP 0 LASTPIN (-5850 3200) $PN DC56
R 1
J 2
(-5860 3190);
DISPLAY 0.489362 (-5860 3190);
PAINT MONO (-5860 3190);
FORCEPROP 0 LASTPIN (-5800 3200) $PN DC58
R 1
J 2
(-5810 3190);
DISPLAY 0.489362 (-5810 3190);
PAINT MONO (-5810 3190);
FORCEPROP 0 LASTPIN (-5750 3200) $PN DC61
R 1
J 2
(-5760 3190);
DISPLAY 0.489362 (-5760 3190);
PAINT MONO (-5760 3190);
FORCEPROP 0 LASTPIN (-5700 3200) $PN DC63
R 1
J 2
(-5710 3190);
DISPLAY 0.489362 (-5710 3190);
PAINT MONO (-5710 3190);
FORCEPROP 0 LASTPIN (-5650 3200) $PN DC65
R 1
J 2
(-5660 3190);
DISPLAY 0.489362 (-5660 3190);
PAINT MONO (-5660 3190);
FORCEPROP 0 LASTPIN (-5600 3200) $PN DC68
R 1
J 2
(-5610 3190);
DISPLAY 0.489362 (-5610 3190);
PAINT MONO (-5610 3190);
FORCEPROP 0 LASTPIN (-5550 3200) $PN DC70
R 1
J 2
(-5560 3190);
DISPLAY 0.489362 (-5560 3190);
PAINT MONO (-5560 3190);
FORCEPROP 0 LASTPIN (-5500 3200) $PN DC72
R 1
J 2
(-5510 3190);
DISPLAY 0.489362 (-5510 3190);
PAINT MONO (-5510 3190);
FORCEPROP 0 LASTPIN (-5450 3200) $PN DC75
R 1
J 2
(-5460 3190);
DISPLAY 0.489362 (-5460 3190);
PAINT MONO (-5460 3190);
FORCEPROP 0 LASTPIN (-5400 3200) $PN DD3
R 1
J 2
(-5410 3190);
DISPLAY 0.489362 (-5410 3190);
PAINT MONO (-5410 3190);
FORCEPROP 0 LASTPIN (-5350 3200) $PN DD5
R 1
J 2
(-5360 3190);
DISPLAY 0.489362 (-5360 3190);
PAINT MONO (-5360 3190);
FORCEPROP 0 LASTPIN (-5300 3200) $PN DD8
R 1
J 2
(-5310 3190);
DISPLAY 0.489362 (-5310 3190);
PAINT MONO (-5310 3190);
FORCEPROP 0 LASTPIN (-5250 3200) $PN DD10
R 1
J 2
(-5260 3190);
DISPLAY 0.489362 (-5260 3190);
PAINT MONO (-5260 3190);
FORCEPROP 0 LASTPIN (-5200 3200) $PN DD12
R 1
J 2
(-5210 3190);
DISPLAY 0.489362 (-5210 3190);
PAINT MONO (-5210 3190);
FORCEPROP 0 LASTPIN (-5150 3200) $PN DD15
R 1
J 2
(-5160 3190);
DISPLAY 0.489362 (-5160 3190);
PAINT MONO (-5160 3190);
FORCEPROP 0 LASTPIN (-5100 3200) $PN DD17
R 1
J 2
(-5110 3190);
DISPLAY 0.489362 (-5110 3190);
PAINT MONO (-5110 3190);
FORCEPROP 0 LASTPIN (-5050 3200) $PN DD19
R 1
J 2
(-5060 3190);
DISPLAY 0.489362 (-5060 3190);
PAINT MONO (-5060 3190);
FORCEPROP 0 LASTPIN (-5000 3200) $PN DD23
R 1
J 2
(-5010 3190);
DISPLAY 0.489362 (-5010 3190);
PAINT MONO (-5010 3190);
FORCEPROP 0 LASTPIN (-4950 3200) $PN DD24
R 1
J 2
(-4960 3190);
DISPLAY 0.489362 (-4960 3190);
PAINT MONO (-4960 3190);
FORCEPROP 0 LASTPIN (-4900 3200) $PN DD26
R 1
J 2
(-4910 3190);
DISPLAY 0.489362 (-4910 3190);
PAINT MONO (-4910 3190);
FORCEPROP 0 LASTPIN (-4850 3200) $PN DD27
R 1
J 2
(-4860 3190);
DISPLAY 0.489362 (-4860 3190);
PAINT MONO (-4860 3190);
FORCEPROP 0 LASTPIN (-4800 3200) $PN DD29
R 1
J 2
(-4810 3190);
DISPLAY 0.489362 (-4810 3190);
PAINT MONO (-4810 3190);
FORCEPROP 0 LASTPIN (-4750 3200) $PN DD30
R 1
J 2
(-4760 3190);
DISPLAY 0.489362 (-4760 3190);
PAINT MONO (-4760 3190);
FORCEPROP 0 LASTPIN (-4700 3200) $PN DD32
R 1
J 2
(-4710 3190);
DISPLAY 0.489362 (-4710 3190);
PAINT MONO (-4710 3190);
FORCEPROP 0 LASTPIN (-4650 3200) $PN DD33
R 1
J 2
(-4660 3190);
DISPLAY 0.489362 (-4660 3190);
PAINT MONO (-4660 3190);
FORCEPROP 0 LASTPIN (-4600 3200) $PN DD35
R 1
J 2
(-4610 3190);
DISPLAY 0.489362 (-4610 3190);
PAINT MONO (-4610 3190);
FORCEPROP 0 LASTPIN (-4550 3200) $PN DD36
R 1
J 2
(-4560 3190);
DISPLAY 0.489362 (-4560 3190);
PAINT MONO (-4560 3190);
FORCEPROP 0 LASTPIN (-4500 3200) $PN DD37
R 1
J 2
(-4510 3190);
DISPLAY 0.489362 (-4510 3190);
PAINT MONO (-4510 3190);
FORCEPROP 0 LASTPIN (-4450 3200) $PN DD39
R 1
J 2
(-4460 3190);
DISPLAY 0.489362 (-4460 3190);
PAINT MONO (-4460 3190);
FORCEPROP 0 LASTPIN (-4400 3200) $PN DD40
R 1
J 2
(-4410 3190);
DISPLAY 0.489362 (-4410 3190);
PAINT MONO (-4410 3190);
FORCEPROP 0 LASTPIN (-4350 3200) $PN DD41
R 1
J 2
(-4360 3190);
DISPLAY 0.489362 (-4360 3190);
PAINT MONO (-4360 3190);
FORCEPROP 0 LASTPIN (-4300 3200) $PN DD43
R 1
J 2
(-4310 3190);
DISPLAY 0.489362 (-4310 3190);
PAINT MONO (-4310 3190);
FORCEPROP 0 LASTPIN (-4250 3200) $PN DD44
R 1
J 2
(-4260 3190);
DISPLAY 0.489362 (-4260 3190);
PAINT MONO (-4260 3190);
FORCEPROP 0 LASTPIN (-4200 3200) $PN DD46
R 1
J 2
(-4210 3190);
DISPLAY 0.489362 (-4210 3190);
PAINT MONO (-4210 3190);
FORCEPROP 0 LASTPIN (-4150 3200) $PN DD47
R 1
J 2
(-4160 3190);
DISPLAY 0.489362 (-4160 3190);
PAINT MONO (-4160 3190);
FORCEPROP 0 LASTPIN (-4100 3200) $PN DD49
R 1
J 2
(-4110 3190);
DISPLAY 0.489362 (-4110 3190);
PAINT MONO (-4110 3190);
FORCEPROP 0 LASTPIN (-4050 3200) $PN DD50
R 1
J 2
(-4060 3190);
DISPLAY 0.489362 (-4060 3190);
PAINT MONO (-4060 3190);
FORCEPROP 0 LASTPIN (-4000 3200) $PN DD52
R 1
J 2
(-4010 3190);
DISPLAY 0.489362 (-4010 3190);
PAINT MONO (-4010 3190);
FORCEPROP 0 LASTPIN (-3950 3200) $PN DD53
R 1
J 2
(-3960 3190);
DISPLAY 0.489362 (-3960 3190);
PAINT MONO (-3960 3190);
FORCEPROP 0 LASTPIN (-3900 3200) $PN DD57
R 1
J 2
(-3910 3190);
DISPLAY 0.489362 (-3910 3190);
PAINT MONO (-3910 3190);
FORCEPROP 0 LASTPIN (-3850 3200) $PN DD59
R 1
J 2
(-3860 3190);
DISPLAY 0.489362 (-3860 3190);
PAINT MONO (-3860 3190);
FORCEPROP 0 LASTPIN (-3800 3200) $PN DD61
R 1
J 2
(-3810 3190);
DISPLAY 0.489362 (-3810 3190);
PAINT MONO (-3810 3190);
FORCEPROP 0 LASTPIN (-3750 3200) $PN DD64
R 1
J 2
(-3760 3190);
DISPLAY 0.489362 (-3760 3190);
PAINT MONO (-3760 3190);
FORCEPROP 0 LASTPIN (-3700 3200) $PN DD66
R 1
J 2
(-3710 3190);
DISPLAY 0.489362 (-3710 3190);
PAINT MONO (-3710 3190);
FORCEPROP 0 LASTPIN (-3650 3200) $PN DD68
R 1
J 2
(-3660 3190);
DISPLAY 0.489362 (-3660 3190);
PAINT MONO (-3660 3190);
FORCEPROP 0 LASTPIN (-3600 3200) $PN DD71
R 1
J 2
(-3610 3190);
DISPLAY 0.489362 (-3610 3190);
PAINT MONO (-3610 3190);
FORCEPROP 0 LASTPIN (-3550 3200) $PN DD73
R 1
J 2
(-3560 3190);
DISPLAY 0.489362 (-3560 3190);
PAINT MONO (-3560 3190);
FORCEPROP 0 LASTPIN (-3500 3200) $PN DE1
R 1
J 2
(-3510 3190);
DISPLAY 0.489362 (-3510 3190);
PAINT MONO (-3510 3190);
FORCEPROP 0 LASTPIN (-3450 3200) $PN DE6
R 1
J 2
(-3460 3190);
DISPLAY 0.489362 (-3460 3190);
PAINT MONO (-3460 3190);
FORCEPROP 0 LASTPIN (-3400 3200) $PN DE8
R 1
J 2
(-3410 3190);
DISPLAY 0.489362 (-3410 3190);
PAINT MONO (-3410 3190);
FORCEPROP 0 LASTPIN (-3350 3200) $PN DE13
R 1
J 2
(-3360 3190);
DISPLAY 0.489362 (-3360 3190);
PAINT MONO (-3360 3190);
FORCEPROP 0 LASTPIN (-3300 3200) $PN DE15
R 1
J 2
(-3310 3190);
DISPLAY 0.489362 (-3310 3190);
PAINT MONO (-3310 3190);
FORCEPROP 0 LASTPIN (-3250 3200) $PN DE20
R 1
J 2
(-3260 3190);
DISPLAY 0.489362 (-3260 3190);
PAINT MONO (-3260 3190);
FORCEPROP 0 LASTPIN (-3200 3200) $PN DE23
R 1
J 2
(-3210 3190);
DISPLAY 0.489362 (-3210 3190);
PAINT MONO (-3210 3190);
FORCEPROP 0 LASTPIN (-3150 3200) $PN DE26
R 1
J 2
(-3160 3190);
DISPLAY 0.489362 (-3160 3190);
PAINT MONO (-3160 3190);
FORCEPROP 0 LASTPIN (-3100 3200) $PN DE29
R 1
J 2
(-3110 3190);
DISPLAY 0.489362 (-3110 3190);
PAINT MONO (-3110 3190);
FORCEPROP 0 LASTPIN (-3050 3200) $PN DE33
R 1
J 2
(-3060 3190);
DISPLAY 0.489362 (-3060 3190);
PAINT MONO (-3060 3190);
FORCEPROP 0 LASTPIN (-3000 3200) $PN DE56
R 1
J 2
(-3010 3190);
DISPLAY 0.489362 (-3010 3190);
PAINT MONO (-3010 3190);
FORCEPROP 0 LASTPIN (-2950 3200) $PN DE61
R 1
J 2
(-2960 3190);
DISPLAY 0.489362 (-2960 3190);
PAINT MONO (-2960 3190);
FORCEPROP 0 LASTPIN (-2900 3200) $PN DE63
R 1
J 2
(-2910 3190);
DISPLAY 0.489362 (-2910 3190);
PAINT MONO (-2910 3190);
FORCEPROP 0 LASTPIN (-2850 3200) $PN DE68
R 1
J 2
(-2860 3190);
DISPLAY 0.489362 (-2860 3190);
PAINT MONO (-2860 3190);
FORCEPROP 0 LASTPIN (-2800 3200) $PN DE70
R 1
J 2
(-2810 3190);
DISPLAY 0.489362 (-2810 3190);
PAINT MONO (-2810 3190);
FORCEPROP 0 LASTPIN (-2750 3200) $PN DE75
R 1
J 2
(-2760 3190);
DISPLAY 0.489362 (-2760 3190);
PAINT MONO (-2760 3190);
FORCEPROP 0 LASTPIN (-2700 3200) $PN DF3
R 1
J 2
(-2710 3190);
DISPLAY 0.489362 (-2710 3190);
PAINT MONO (-2710 3190);
FORCEPROP 0 LASTPIN (-2650 3200) $PN DF4
R 1
J 2
(-2660 3190);
DISPLAY 0.489362 (-2660 3190);
PAINT MONO (-2660 3190);
FORCEPROP 0 LASTPIN (-2600 3200) $PN DF5
R 1
J 2
(-2610 3190);
DISPLAY 0.489362 (-2610 3190);
PAINT MONO (-2610 3190);
FORCEPROP 0 LASTPIN (-2550 3200) $PN DF6
R 1
J 2
(-2560 3190);
DISPLAY 0.489362 (-2560 3190);
PAINT MONO (-2560 3190);
FORCEPROP 0 LASTPIN (-2500 3200) $PN DF8
R 1
J 2
(-2510 3190);
DISPLAY 0.489362 (-2510 3190);
PAINT MONO (-2510 3190);
FORCEPROP 0 LASTPIN (-2450 3200) $PN DF10
R 1
J 2
(-2460 3190);
DISPLAY 0.489362 (-2460 3190);
PAINT MONO (-2460 3190);
FORCEPROP 0 LASTPIN (-2400 3200) $PN DF11
R 1
J 2
(-2410 3190);
DISPLAY 0.489362 (-2410 3190);
PAINT MONO (-2410 3190);
FORCEPROP 0 LASTPIN (-2350 3200) $PN DF12
R 1
J 2
(-2360 3190);
DISPLAY 0.489362 (-2360 3190);
PAINT MONO (-2360 3190);
FORCEPROP 0 LASTPIN (-2300 3200) $PN DF13
R 1
J 2
(-2310 3190);
DISPLAY 0.489362 (-2310 3190);
PAINT MONO (-2310 3190);
FORCEPROP 0 LASTPIN (-2250 3200) $PN DF15
R 1
J 2
(-2260 3190);
DISPLAY 0.489362 (-2260 3190);
PAINT MONO (-2260 3190);
FORCEPROP 0 LASTPIN (-2200 3200) $PN DF17
R 1
J 2
(-2210 3190);
DISPLAY 0.489362 (-2210 3190);
PAINT MONO (-2210 3190);
FORCEPROP 0 LASTPIN (-2150 3200) $PN DF18
R 1
J 2
(-2160 3190);
DISPLAY 0.489362 (-2160 3190);
PAINT MONO (-2160 3190);
FORCEPROP 0 LASTPIN (-2100 3200) $PN DF19
R 1
J 2
(-2110 3190);
DISPLAY 0.489362 (-2110 3190);
PAINT MONO (-2110 3190);
FORCEPROP 0 LASTPIN (-8000 4300) $PN DF20
R 1
J 0
(-8010 4310);
DISPLAY 0.489362 (-8010 4310);
PAINT MONO (-8010 4310);
FORCEPROP 0 LASTPIN (-7950 4300) $PN DF22
R 1
J 0
(-7960 4310);
DISPLAY 0.489362 (-7960 4310);
PAINT MONO (-7960 4310);
FORCEPROP 0 LASTPIN (-7900 4300) $PN DF23
R 1
J 0
(-7910 4310);
DISPLAY 0.489362 (-7910 4310);
PAINT MONO (-7910 4310);
FORCEPROP 0 LASTPIN (-7850 4300) $PN DF26
R 1
J 0
(-7860 4310);
DISPLAY 0.489362 (-7860 4310);
PAINT MONO (-7860 4310);
FORCEPROP 0 LASTPIN (-7800 4300) $PN DF29
R 1
J 0
(-7810 4310);
DISPLAY 0.489362 (-7810 4310);
PAINT MONO (-7810 4310);
FORCEPROP 0 LASTPIN (-7750 4300) $PN DF32
R 1
J 0
(-7760 4310);
DISPLAY 0.489362 (-7760 4310);
PAINT MONO (-7760 4310);
FORCEPROP 0 LASTPIN (-7700 4300) $PN DF35
R 1
J 0
(-7710 4310);
DISPLAY 0.489362 (-7710 4310);
PAINT MONO (-7710 4310);
FORCEPROP 0 LASTPIN (-7650 4300) $PN DF37
R 1
J 0
(-7660 4310);
DISPLAY 0.489362 (-7660 4310);
PAINT MONO (-7660 4310);
FORCEPROP 0 LASTPIN (-7600 4300) $PN DF39
R 1
J 0
(-7610 4310);
DISPLAY 0.489362 (-7610 4310);
PAINT MONO (-7610 4310);
FORCEPROP 0 LASTPIN (-7550 4300) $PN DF42
R 1
J 0
(-7560 4310);
DISPLAY 0.489362 (-7560 4310);
PAINT MONO (-7560 4310);
FORCEPROP 0 LASTPIN (-7500 4300) $PN DF43
R 1
J 0
(-7510 4310);
DISPLAY 0.489362 (-7510 4310);
PAINT MONO (-7510 4310);
FORCEPROP 0 LASTPIN (-7450 4300) $PN DF44
R 1
J 0
(-7460 4310);
DISPLAY 0.489362 (-7460 4310);
PAINT MONO (-7460 4310);
FORCEPROP 0 LASTPIN (-7400 4300) $PN DF45
R 1
J 0
(-7410 4310);
DISPLAY 0.489362 (-7410 4310);
PAINT MONO (-7410 4310);
FORCEPROP 0 LASTPIN (-7350 4300) $PN DF46
R 1
J 0
(-7360 4310);
DISPLAY 0.489362 (-7360 4310);
PAINT MONO (-7360 4310);
FORCEPROP 0 LASTPIN (-7300 4300) $PN DF47
R 1
J 0
(-7310 4310);
DISPLAY 0.489362 (-7310 4310);
PAINT MONO (-7310 4310);
FORCEPROP 0 LASTPIN (-7250 4300) $PN DF48
R 1
J 0
(-7260 4310);
DISPLAY 0.489362 (-7260 4310);
PAINT MONO (-7260 4310);
FORCEPROP 0 LASTPIN (-7200 4300) $PN DF49
R 1
J 0
(-7210 4310);
DISPLAY 0.489362 (-7210 4310);
PAINT MONO (-7210 4310);
FORCEPROP 0 LASTPIN (-7150 4300) $PN DF50
R 1
J 0
(-7160 4310);
DISPLAY 0.489362 (-7160 4310);
PAINT MONO (-7160 4310);
FORCEPROP 0 LASTPIN (-7100 4300) $PN DF51
R 1
J 0
(-7110 4310);
DISPLAY 0.489362 (-7110 4310);
PAINT MONO (-7110 4310);
FORCEPROP 0 LASTPIN (-7050 4300) $PN DF52
R 1
J 0
(-7060 4310);
DISPLAY 0.489362 (-7060 4310);
PAINT MONO (-7060 4310);
FORCEPROP 0 LASTPIN (-7000 4300) $PN DF53
R 1
J 0
(-7010 4310);
DISPLAY 0.489362 (-7010 4310);
PAINT MONO (-7010 4310);
FORCEPROP 0 LASTPIN (-6950 4300) $PN DF54
R 1
J 0
(-6960 4310);
DISPLAY 0.489362 (-6960 4310);
PAINT MONO (-6960 4310);
FORCEPROP 0 LASTPIN (-6900 4300) $PN DF56
R 1
J 0
(-6910 4310);
DISPLAY 0.489362 (-6910 4310);
PAINT MONO (-6910 4310);
FORCEPROP 0 LASTPIN (-6850 4300) $PN DF57
R 1
J 0
(-6860 4310);
DISPLAY 0.489362 (-6860 4310);
PAINT MONO (-6860 4310);
FORCEPROP 0 LASTPIN (-6800 4300) $PN DF58
R 1
J 0
(-6810 4310);
DISPLAY 0.489362 (-6810 4310);
PAINT MONO (-6810 4310);
FORCEPROP 0 LASTPIN (-6750 4300) $PN DF59
R 1
J 0
(-6760 4310);
DISPLAY 0.489362 (-6760 4310);
PAINT MONO (-6760 4310);
FORCEPROP 0 LASTPIN (-6700 4300) $PN DF61
R 1
J 0
(-6710 4310);
DISPLAY 0.489362 (-6710 4310);
PAINT MONO (-6710 4310);
FORCEPROP 0 LASTPIN (-6650 4300) $PN DF63
R 1
J 0
(-6660 4310);
DISPLAY 0.489362 (-6660 4310);
PAINT MONO (-6660 4310);
FORCEPROP 0 LASTPIN (-6600 4300) $PN DF64
R 1
J 0
(-6610 4310);
DISPLAY 0.489362 (-6610 4310);
PAINT MONO (-6610 4310);
FORCEPROP 0 LASTPIN (-6550 4300) $PN DF65
R 1
J 0
(-6560 4310);
DISPLAY 0.489362 (-6560 4310);
PAINT MONO (-6560 4310);
FORCEPROP 0 LASTPIN (-6500 4300) $PN DF66
R 1
J 0
(-6510 4310);
DISPLAY 0.489362 (-6510 4310);
PAINT MONO (-6510 4310);
FORCEPROP 0 LASTPIN (-6450 4300) $PN DF68
R 1
J 0
(-6460 4310);
DISPLAY 0.489362 (-6460 4310);
PAINT MONO (-6460 4310);
FORCEPROP 0 LASTPIN (-6400 4300) $PN DF70
R 1
J 0
(-6410 4310);
DISPLAY 0.489362 (-6410 4310);
PAINT MONO (-6410 4310);
FORCEPROP 0 LASTPIN (-6350 4300) $PN DF71
R 1
J 0
(-6360 4310);
DISPLAY 0.489362 (-6360 4310);
PAINT MONO (-6360 4310);
FORCEPROP 0 LASTPIN (-6300 4300) $PN DF72
R 1
J 0
(-6310 4310);
DISPLAY 0.489362 (-6310 4310);
PAINT MONO (-6310 4310);
FORCEPROP 0 LASTPIN (-6250 4300) $PN DF73
R 1
J 0
(-6260 4310);
DISPLAY 0.489362 (-6260 4310);
PAINT MONO (-6260 4310);
FORCEPROP 0 LASTPIN (-6200 4300) $PN DG1
R 1
J 0
(-6210 4310);
DISPLAY 0.489362 (-6210 4310);
PAINT MONO (-6210 4310);
FORCEPROP 0 LASTPIN (-6150 4300) $PN DG2
R 1
J 0
(-6160 4310);
DISPLAY 0.489362 (-6160 4310);
PAINT MONO (-6160 4310);
FORCEPROP 0 LASTPIN (-6100 4300) $PN DG6
R 1
J 0
(-6110 4310);
DISPLAY 0.489362 (-6110 4310);
PAINT MONO (-6110 4310);
FORCEPROP 0 LASTPIN (-6050 4300) $PN DG7
R 1
J 0
(-6060 4310);
DISPLAY 0.489362 (-6060 4310);
PAINT MONO (-6060 4310);
FORCEPROP 0 LASTPIN (-6000 4300) $PN DG8
R 1
J 0
(-6010 4310);
DISPLAY 0.489362 (-6010 4310);
PAINT MONO (-6010 4310);
FORCEPROP 0 LASTPIN (-5950 4300) $PN DG9
R 1
J 0
(-5960 4310);
DISPLAY 0.489362 (-5960 4310);
PAINT MONO (-5960 4310);
FORCEPROP 0 LASTPIN (-5900 4300) $PN DG13
R 1
J 0
(-5910 4310);
DISPLAY 0.489362 (-5910 4310);
PAINT MONO (-5910 4310);
FORCEPROP 0 LASTPIN (-5850 4300) $PN DG14
R 1
J 0
(-5860 4310);
DISPLAY 0.489362 (-5860 4310);
PAINT MONO (-5860 4310);
FORCEPROP 0 LASTPIN (-5800 4300) $PN DG15
R 1
J 0
(-5810 4310);
DISPLAY 0.489362 (-5810 4310);
PAINT MONO (-5810 4310);
FORCEPROP 0 LASTPIN (-5750 4300) $PN DG16
R 1
J 0
(-5760 4310);
DISPLAY 0.489362 (-5760 4310);
PAINT MONO (-5760 4310);
FORCEPROP 0 LASTPIN (-5700 4300) $PN DG18
R 1
J 0
(-5710 4310);
DISPLAY 0.489362 (-5710 4310);
PAINT MONO (-5710 4310);
FORCEPROP 0 LASTPIN (-5650 4300) $PN DG20
R 1
J 0
(-5660 4310);
DISPLAY 0.489362 (-5660 4310);
PAINT MONO (-5660 4310);
FORCEPROP 0 LASTPIN (-5600 4300) $PN DG21
R 1
J 0
(-5610 4310);
DISPLAY 0.489362 (-5610 4310);
PAINT MONO (-5610 4310);
FORCEPROP 0 LASTPIN (-5550 4300) $PN DG24
R 1
J 0
(-5560 4310);
DISPLAY 0.489362 (-5560 4310);
PAINT MONO (-5560 4310);
FORCEPROP 0 LASTPIN (-5500 4300) $PN DG27
R 1
J 0
(-5510 4310);
DISPLAY 0.489362 (-5510 4310);
PAINT MONO (-5510 4310);
FORCEPROP 0 LASTPIN (-5450 4300) $PN DG30
R 1
J 0
(-5460 4310);
DISPLAY 0.489362 (-5460 4310);
PAINT MONO (-5460 4310);
FORCEPROP 0 LASTPIN (-5400 4300) $PN DG33
R 1
J 0
(-5410 4310);
DISPLAY 0.489362 (-5410 4310);
PAINT MONO (-5410 4310);
FORCEPROP 0 LASTPIN (-5350 4300) $PN DG41
R 1
J 0
(-5360 4310);
DISPLAY 0.489362 (-5360 4310);
PAINT MONO (-5360 4310);
FORCEPROP 0 LASTPIN (-5300 4300) $PN DG43
R 1
J 0
(-5310 4310);
DISPLAY 0.489362 (-5310 4310);
PAINT MONO (-5310 4310);
FORCEPROP 0 LASTPIN (-5250 4300) $PN DG46
R 1
J 0
(-5260 4310);
DISPLAY 0.489362 (-5260 4310);
PAINT MONO (-5260 4310);
FORCEPROP 0 LASTPIN (-5200 4300) $PN DG49
R 1
J 0
(-5210 4310);
DISPLAY 0.489362 (-5210 4310);
PAINT MONO (-5210 4310);
FORCEPROP 0 LASTPIN (-5150 4300) $PN DG52
R 1
J 0
(-5160 4310);
DISPLAY 0.489362 (-5160 4310);
PAINT MONO (-5160 4310);
FORCEPROP 0 LASTPIN (-5100 4300) $PN DG55
R 1
J 0
(-5110 4310);
DISPLAY 0.489362 (-5110 4310);
PAINT MONO (-5110 4310);
FORCEPROP 0 LASTPIN (-5050 4300) $PN DG56
R 1
J 0
(-5060 4310);
DISPLAY 0.489362 (-5060 4310);
PAINT MONO (-5060 4310);
FORCEPROP 0 LASTPIN (-5000 4300) $PN DG59
R 1
J 0
(-5010 4310);
DISPLAY 0.489362 (-5010 4310);
PAINT MONO (-5010 4310);
FORCEPROP 0 LASTPIN (-4950 4300) $PN DG60
R 1
J 0
(-4960 4310);
DISPLAY 0.489362 (-4960 4310);
PAINT MONO (-4960 4310);
FORCEPROP 0 LASTPIN (-4900 4300) $PN DG61
R 1
J 0
(-4910 4310);
DISPLAY 0.489362 (-4910 4310);
PAINT MONO (-4910 4310);
FORCEPROP 0 LASTPIN (-4850 4300) $PN DG62
R 1
J 0
(-4860 4310);
DISPLAY 0.489362 (-4860 4310);
PAINT MONO (-4860 4310);
FORCEPROP 0 LASTPIN (-4800 4300) $PN DG63
R 1
J 0
(-4810 4310);
DISPLAY 0.489362 (-4810 4310);
PAINT MONO (-4810 4310);
FORCEPROP 0 LASTPIN (-4750 4300) $PN DG65
R 1
J 0
(-4760 4310);
DISPLAY 0.489362 (-4760 4310);
PAINT MONO (-4760 4310);
FORCEPROP 0 LASTPIN (-4700 4300) $PN DG66
R 1
J 0
(-4710 4310);
DISPLAY 0.489362 (-4710 4310);
PAINT MONO (-4710 4310);
FORCEPROP 0 LASTPIN (-4650 4300) $PN DG67
R 1
J 0
(-4660 4310);
DISPLAY 0.489362 (-4660 4310);
PAINT MONO (-4660 4310);
FORCEPROP 0 LASTPIN (-4600 4300) $PN DG68
R 1
J 0
(-4610 4310);
DISPLAY 0.489362 (-4610 4310);
PAINT MONO (-4610 4310);
FORCEPROP 0 LASTPIN (-4550 4300) $PN DG69
R 1
J 0
(-4560 4310);
DISPLAY 0.489362 (-4560 4310);
PAINT MONO (-4560 4310);
FORCEPROP 0 LASTPIN (-4500 4300) $PN DG70
R 1
J 0
(-4510 4310);
DISPLAY 0.489362 (-4510 4310);
PAINT MONO (-4510 4310);
FORCEPROP 0 LASTPIN (-4450 4300) $PN DG74
R 1
J 0
(-4460 4310);
DISPLAY 0.489362 (-4460 4310);
PAINT MONO (-4460 4310);
FORCEPROP 0 LASTPIN (-4400 4300) $PN DG75
R 1
J 0
(-4410 4310);
DISPLAY 0.489362 (-4410 4310);
PAINT MONO (-4410 4310);
FORCEPROP 0 LASTPIN (-4350 4300) $PN DH5
R 1
J 0
(-4360 4310);
DISPLAY 0.489362 (-4360 4310);
PAINT MONO (-4360 4310);
FORCEPROP 0 LASTPIN (-4300 4300) $PN DH11
R 1
J 0
(-4310 4310);
DISPLAY 0.489362 (-4310 4310);
PAINT MONO (-4310 4310);
FORCEPROP 0 LASTPIN (-4250 4300) $PN DH18
R 1
J 0
(-4260 4310);
DISPLAY 0.489362 (-4260 4310);
PAINT MONO (-4260 4310);
FORCEPROP 0 LASTPIN (-4200 4300) $PN DH37
R 1
J 0
(-4210 4310);
DISPLAY 0.489362 (-4210 4310);
PAINT MONO (-4210 4310);
FORCEPROP 0 LASTPIN (-4150 4300) $PN DH39
R 1
J 0
(-4160 4310);
DISPLAY 0.489362 (-4160 4310);
PAINT MONO (-4160 4310);
FORCEPROP 0 LASTPIN (-4100 4300) $PN DH43
R 1
J 0
(-4110 4310);
DISPLAY 0.489362 (-4110 4310);
PAINT MONO (-4110 4310);
FORCEPROP 0 LASTPIN (-4050 4300) $PN DH46
R 1
J 0
(-4060 4310);
DISPLAY 0.489362 (-4060 4310);
PAINT MONO (-4060 4310);
FORCEPROP 0 LASTPIN (-4000 4300) $PN DH49
R 1
J 0
(-4010 4310);
DISPLAY 0.489362 (-4010 4310);
PAINT MONO (-4010 4310);
FORCEPROP 0 LASTPIN (-3950 4300) $PN DH52
R 1
J 0
(-3960 4310);
DISPLAY 0.489362 (-3960 4310);
PAINT MONO (-3960 4310);
FORCEPROP 0 LASTPIN (-3900 4300) $PN DH55
R 1
J 0
(-3910 4310);
DISPLAY 0.489362 (-3910 4310);
PAINT MONO (-3910 4310);
FORCEPROP 0 LASTPIN (-3850 4300) $PN DH59
R 1
J 0
(-3860 4310);
DISPLAY 0.489362 (-3860 4310);
PAINT MONO (-3860 4310);
FORCEPROP 0 LASTPIN (-3800 4300) $PN DH61
R 1
J 0
(-3810 4310);
DISPLAY 0.489362 (-3810 4310);
PAINT MONO (-3810 4310);
FORCEPROP 0 LASTPIN (-3750 4300) $PN DH63
R 1
J 0
(-3760 4310);
DISPLAY 0.489362 (-3760 4310);
PAINT MONO (-3760 4310);
FORCEPROP 0 LASTPIN (-3700 4300) $PN DH64
R 1
J 0
(-3710 4310);
DISPLAY 0.489362 (-3710 4310);
PAINT MONO (-3710 4310);
FORCEPROP 0 LASTPIN (-3650 4300) $PN DH66
R 1
J 0
(-3660 4310);
DISPLAY 0.489362 (-3660 4310);
PAINT MONO (-3660 4310);
FORCEPROP 0 LASTPIN (-3600 4300) $PN DH68
R 1
J 0
(-3610 4310);
DISPLAY 0.489362 (-3610 4310);
PAINT MONO (-3610 4310);
FORCEPROP 0 LASTPIN (-3550 4300) $PN DH70
R 1
J 0
(-3560 4310);
DISPLAY 0.489362 (-3560 4310);
PAINT MONO (-3560 4310);
FORCEPROP 0 LASTPIN (-3500 4300) $PN DJ7
R 1
J 0
(-3510 4310);
DISPLAY 0.489362 (-3510 4310);
PAINT MONO (-3510 4310);
FORCEPROP 0 LASTPIN (-3450 4300) $PN DJ15
R 1
J 0
(-3460 4310);
DISPLAY 0.489362 (-3460 4310);
PAINT MONO (-3460 4310);
FORCEPROP 0 LASTPIN (-3400 4300) $PN DJ19
R 1
J 0
(-3410 4310);
DISPLAY 0.489362 (-3410 4310);
PAINT MONO (-3410 4310);
FORCEPROP 0 LASTPIN (-3350 4300) $PN DJ43
R 1
J 0
(-3360 4310);
DISPLAY 0.489362 (-3360 4310);
PAINT MONO (-3360 4310);
FORCEPROP 0 LASTPIN (-3300 4300) $PN DJ49
R 1
J 0
(-3310 4310);
DISPLAY 0.489362 (-3310 4310);
PAINT MONO (-3310 4310);
FORCEPROP 0 LASTPIN (-3250 4300) $PN DJ59
R 1
J 0
(-3260 4310);
DISPLAY 0.489362 (-3260 4310);
PAINT MONO (-3260 4310);
FORCEPROP 0 LASTPIN (-3200 4300) $PN DJ61
R 1
J 0
(-3210 4310);
DISPLAY 0.489362 (-3210 4310);
PAINT MONO (-3210 4310);
FORCEPROP 0 LASTPIN (-3150 4300) $PN DJ63
R 1
J 0
(-3160 4310);
DISPLAY 0.489362 (-3160 4310);
PAINT MONO (-3160 4310);
FORCEPROP 0 LASTPIN (-3100 4300) $PN DJ66
R 1
J 0
(-3110 4310);
DISPLAY 0.489362 (-3110 4310);
PAINT MONO (-3110 4310);
FORCEPROP 0 LASTPIN (-3050 4300) $PN DJ68
R 1
J 0
(-3060 4310);
DISPLAY 0.489362 (-3060 4310);
PAINT MONO (-3060 4310);
FORCEPROP 0 LASTPIN (-3000 4300) $PN DJ73
R 1
J 0
(-3010 4310);
DISPLAY 0.489362 (-3010 4310);
PAINT MONO (-3010 4310);
FORCEPROP 0 LASTPIN (-2950 4300) $PN K23
R 1
J 0
(-2960 4310);
DISPLAY 0.489362 (-2960 4310);
PAINT MONO (-2960 4310);
FORCEPROP 0 LASTPIN (-2900 4300) $PN K59
R 1
J 0
(-2910 4310);
DISPLAY 0.489362 (-2910 4310);
PAINT MONO (-2910 4310);
FORCEPROP 0 LASTPIN (-2850 4300) $PN P25
R 1
J 0
(-2860 4310);
DISPLAY 0.489362 (-2860 4310);
PAINT MONO (-2860 4310);
FORCEPROP 0 LASTPIN (-2800 4300) $PN P68
R 1
J 0
(-2810 4310);
DISPLAY 0.489362 (-2810 4310);
PAINT MONO (-2810 4310);
FORCEPROP 0 LASTPIN (-2750 4300) $PN V27
R 1
J 0
(-2760 4310);
DISPLAY 0.489362 (-2760 4310);
PAINT MONO (-2760 4310);
FORCEPROP 0 LASTPIN (-2700 4300) $PN V68
R 1
J 0
(-2710 4310);
DISPLAY 0.489362 (-2710 4310);
PAINT MONO (-2710 4310);
FORCEPROP 2 LAST PART_TYPE SMLF
R 1
J 0
(-8575 3375);
DISPLAY 1.021277 (-8575 3375);
FORCEPROP 1 LAST MATERIAL IO
R 1
J 0
(-8132 3355);
DISPLAY 0.489362 (-8132 3355);
PAINT SKYBLUE (-8132 3355);
FORCEPROP 2 LAST VALUE SOCKET6096_13568-001
R 1
J 0
(-8200 3350);
DISPLAY 0.489362 (-8200 3350);
PAINT SKYBLUE (-8200 3350);
FORCEPROP 1 LAST CDS_LMAN_SYM_OUTLINE -400,3350,400,-3350
R 1
J 0
(-4750 3750);
DISPLAY 0.468085 (-4750 3750);
PAINT GREEN (-4750 3750);
DISPLAY INVISIBLE (-4750 3750);
FORCEPROP 2 LAST CDS_LIB pure_quanta
J 0
(-4750 3750);
DISPLAY INVISIBLE (-4750 3750);
FORCEPROP 1 LAST NEEDS_NO_SIZE TRUE
R 1
J 0
(-4750 3750);
DISPLAY 0.723404 (-4750 3750);
PAINT GREEN (-4750 3750);
DISPLAY INVISIBLE (-4750 3750);
FORCEPROP 1 LAST PATH I4
R 1
J 0
(-4750 3750);
DISPLAY 0.723404 (-4750 3750);
PAINT GREEN (-4750 3750);
DISPLAY INVISIBLE (-4750 3750);
FORCEPROP 1 LAST PART_NUMBER DGA^6000030
R 1
J 0
(-8259 3355);
DISPLAY 0.489362 (-8259 3355);
PAINT SKYBLUE (-8259 3355);
DISPLAY INVISIBLE (-8259 3355);
FORCEADD UNIVERSAL_GND..1
R 1
(-1300 4475);
FORCEPROP 3 LASTPIN (-1350 4475) SIG_NAME GND\g
J 0
(-1340 4485);
DISPLAY 0.659574 (-1340 4485);
PAINT MONO (-1340 4485);
DISPLAY INVISIBLE (-1340 4485);
FORCEPROP 2 LAST CDS_LIB pure_quanta_power
R 1
J 0
(-1300 4475);
DISPLAY INVISIBLE (-1300 4475);
FORCEPROP 1 LAST HDL_POWER GND
R 1
J 1
(-1225 4500);
DISPLAY 0.872340 (-1225 4500);
PAINT GREEN (-1225 4500);
DISPLAY INVISIBLE (-1225 4500);
FORCEPROP 1 LAST PATH I5
R 1
J 0
(-1300 4550);
DISPLAY 0.872340 (-1300 4550);
PAINT AQUA (-1300 4550);
DISPLAY INVISIBLE (-1300 4550);
FORCEADD UNIVERSAL_GND..1
R 1
(-1875 3025);
FORCEPROP 3 LASTPIN (-1925 3025) SIG_NAME GND\g
J 0
(-1915 3035);
DISPLAY 0.659574 (-1915 3035);
PAINT MONO (-1915 3035);
DISPLAY INVISIBLE (-1915 3035);
FORCEPROP 2 LAST CDS_LIB pure_quanta_power
R 1
J 0
(-1875 3025);
DISPLAY INVISIBLE (-1875 3025);
FORCEPROP 1 LAST HDL_POWER GND
R 1
J 1
(-1800 3050);
DISPLAY 0.872340 (-1800 3050);
PAINT GREEN (-1800 3050);
DISPLAY INVISIBLE (-1800 3050);
FORCEPROP 1 LAST PATH I6
R 1
J 0
(-1875 3100);
DISPLAY 0.872340 (-1875 3100);
PAINT AQUA (-1875 3100);
DISPLAY INVISIBLE (-1875 3100);
FORCEADD QUANTA_TITLE_BLOCK_C..1
(-100 100);
FORCEPROP 0 LAST CDS_CON_LAST_MODIFIED Thu Sep 14 16:11:55 2023
J 0
(-1985 115);
DISPLAY INVISIBLE (-1985 115);
FORCEPROP 1 LAST CUSTOM_TXT_CDS <CON_LAST_MODIFIED>
J 0
(-1985 115);
DISPLAY 0.978723 (-1985 115);
FORCEPROP 2 LAST CUSTOM_TXT_CDS <XR_PAGE_TITLE>
J 0
(-7990 5350);
DISPLAY 0.638298 (-7990 5350);
PAINT PINK (-7990 5350);
DISPLAY INVISIBLE (-7990 5350);
FORCEPROP 1 LAST CUSTOM_TXT_CDS <NAME_2>
J 0
(-3275 150);
FORCEPROP 1 LAST CUSTOM_TXT_CDS <NAME_1>
J 0
(-3275 275);
FORCEPROP 1 LAST CUSTOM_TXT_CDS <Q_NUMBER>
J 0
(-1503 203);
DISPLAY 1.212766 (-1503 203);
FORCEPROP 1 LAST CUSTOM_TXT_CDS <Q_PROJ>
J 0
(-2482 202);
DISPLAY 1.212766 (-2482 202);
FORCEPROP 1 LAST CUSTOM_TXT_CDS <Q_REV>
J 0
(-284 203);
DISPLAY 1.212766 (-284 203);
FORCEPROP 1 LAST CUSTOM_TXT_CDS <CON_PAGE_NUM> OF <CON_TOTAL_PAGES>
J 0
(-546 118);
DISPLAY 0.978723 (-546 118);
FORCEPROP 1 LAST Q_TITLE CPU0 VSS 3/3
J 0
(-9400 175);
DISPLAY 2.446809 (-9400 175);
PAINT GREEN (-9400 175);
FORCEPROP 2 LAST PAGE_BORDER TRUE
J 0
(-7990 5350);
DISPLAY 0.638298 (-7990 5350);
PAINT PINK (-7990 5350);
DISPLAY INVISIBLE (-7990 5350);
FORCEPROP 1 LAST CDS_LMAN_SYM_OUTLINE -9475,6775,100,-125
J 0
(-100 100);
DISPLAY 0.468085 (-100 100);
PAINT GREEN (-100 100);
DISPLAY INVISIBLE (-100 100);
FORCEPROP 2 LAST CDS_LIB pure_quanta
J 0
(-100 100);
DISPLAY INVISIBLE (-100 100);
FORCEPROP 2 LAST CDS_XR_PAGE_TITLE CR-33 : @T6G_MB_LIB.T6G(SCH_1):PAGE33
J 0
(-7990 5350);
DISPLAY 0.638298 (-7990 5350);
PAINT PINK (-7990 5350);
DISPLAY INVISIBLE (-7990 5350);
FORCEPROP 1 LAST Q_DEPT BU9
J 1
(-3863 149);
DISPLAY 1.957447 (-3863 149);
PAINT GREEN (-3863 149);
DISPLAY INVISIBLE (-3863 149);
FORCEPROP 1 LAST COMMENT_BODY TRUE
J 0
(-88 87);
DISPLAY 0.978723 (-88 87);
PAINT GREEN (-88 87);
DISPLAY INVISIBLE (-88 87);
WIRE 16 -1 (-1350 4475)(-1600 4475);
WIRE 16 -1 (-1600 4475)(-1650 4475);
WIRE 16 -1 (-1600 4475)(-1600 4300);
WIRE 16 -1 (-1650 4475)(-1700 4475);
WIRE 16 -1 (-1650 4475)(-1650 4300);
WIRE 16 -1 (-1700 4475)(-1750 4475);
WIRE 16 -1 (-1700 4475)(-1700 4300);
WIRE 16 -1 (-1750 4475)(-1750 4300);
WIRE 16 -1 (-1750 4475)(-1800 4475);
WIRE 16 -1 (-1800 4475)(-1850 4475);
WIRE 16 -1 (-1800 4300)(-1800 4475);
WIRE 16 -1 (-1850 4475)(-1900 4475);
WIRE 16 -1 (-1850 4300)(-1850 4475);
WIRE 16 -1 (-1900 4475)(-1950 4475);
WIRE 16 -1 (-1900 4300)(-1900 4475);
WIRE 16 -1 (-1950 4475)(-2000 4475);
WIRE 16 -1 (-1950 4300)(-1950 4475);
WIRE 16 -1 (-2000 4300)(-2000 4475);
WIRE 16 -1 (-2000 4475)(-2050 4475);
WIRE 16 -1 (-2050 4475)(-2100 4475);
WIRE 16 -1 (-2050 4300)(-2050 4475);
WIRE 16 -1 (-2100 4475)(-2150 4475);
WIRE 16 -1 (-2100 4300)(-2100 4475);
WIRE 16 -1 (-2200 4475)(-2150 4475);
WIRE 16 -1 (-2150 4300)(-2150 4475);
WIRE 16 -1 (-2250 4475)(-2200 4475);
WIRE 16 -1 (-2200 4300)(-2200 4475);
WIRE 16 -1 (-2300 4475)(-2250 4475);
WIRE 16 -1 (-2250 4300)(-2250 4475);
WIRE 16 -1 (-2300 4300)(-2300 4475);
WIRE 16 -1 (-2350 4475)(-2300 4475);
WIRE 16 -1 (-2400 4475)(-2350 4475);
WIRE 16 -1 (-2350 4300)(-2350 4475);
WIRE 16 -1 (-2450 4475)(-2400 4475);
WIRE 16 -1 (-2400 4300)(-2400 4475);
WIRE 16 -1 (-2500 4475)(-2450 4475);
WIRE 16 -1 (-2450 4300)(-2450 4475);
WIRE 16 -1 (-2550 4475)(-2500 4475);
WIRE 16 -1 (-2500 4300)(-2500 4475);
WIRE 16 -1 (-2550 4300)(-2550 4475);
WIRE 16 -1 (-2600 4475)(-2550 4475);
WIRE 16 -1 (-2650 4475)(-2600 4475);
WIRE 16 -1 (-2600 4300)(-2600 4475);
WIRE 16 -1 (-2700 4475)(-2650 4475);
WIRE 16 -1 (-2650 4300)(-2650 4475);
WIRE 16 -1 (-2750 4475)(-2700 4475);
WIRE 16 -1 (-2700 4300)(-2700 4475);
WIRE 16 -1 (-2800 4475)(-2750 4475);
WIRE 16 -1 (-2750 4300)(-2750 4475);
WIRE 16 -1 (-2800 4300)(-2800 4475);
WIRE 16 -1 (-2850 4475)(-2800 4475);
WIRE 16 -1 (-2900 4475)(-2850 4475);
WIRE 16 -1 (-2850 4300)(-2850 4475);
WIRE 16 -1 (-2950 4475)(-2900 4475);
WIRE 16 -1 (-2900 4300)(-2900 4475);
WIRE 16 -1 (-3000 4475)(-2950 4475);
WIRE 16 -1 (-2950 4300)(-2950 4475);
WIRE 16 -1 (-3050 4475)(-3000 4475);
WIRE 16 -1 (-3000 4300)(-3000 4475);
WIRE 16 -1 (-3050 4300)(-3050 4475);
WIRE 16 -1 (-3100 4475)(-3050 4475);
WIRE 16 -1 (-3150 4475)(-3100 4475);
WIRE 16 -1 (-3100 4300)(-3100 4475);
WIRE 16 -1 (-3200 4475)(-3150 4475);
WIRE 16 -1 (-3150 4300)(-3150 4475);
WIRE 16 -1 (-3250 4475)(-3200 4475);
WIRE 16 -1 (-3200 4300)(-3200 4475);
WIRE 16 -1 (-3300 4475)(-3250 4475);
WIRE 16 -1 (-3250 4300)(-3250 4475);
WIRE 16 -1 (-3300 4300)(-3300 4475);
WIRE 16 -1 (-3350 4475)(-3300 4475);
WIRE 16 -1 (-3400 4475)(-3350 4475);
WIRE 16 -1 (-3350 4300)(-3350 4475);
WIRE 16 -1 (-3450 4475)(-3400 4475);
WIRE 16 -1 (-3400 4300)(-3400 4475);
WIRE 16 -1 (-3500 4475)(-3450 4475);
WIRE 16 -1 (-3450 4300)(-3450 4475);
WIRE 16 -1 (-3550 4475)(-3500 4475);
WIRE 16 -1 (-3500 4300)(-3500 4475);
WIRE 16 -1 (-3550 4300)(-3550 4475);
WIRE 16 -1 (-3600 4475)(-3550 4475);
WIRE 16 -1 (-3650 4475)(-3600 4475);
WIRE 16 -1 (-3600 4300)(-3600 4475);
WIRE 16 -1 (-3700 4475)(-3650 4475);
WIRE 16 -1 (-3650 4300)(-3650 4475);
WIRE 16 -1 (-3750 4475)(-3700 4475);
WIRE 16 -1 (-3700 4300)(-3700 4475);
WIRE 16 -1 (-3800 4475)(-3750 4475);
WIRE 16 -1 (-3750 4300)(-3750 4475);
WIRE 16 -1 (-3800 4300)(-3800 4475);
WIRE 16 -1 (-3850 4475)(-3800 4475);
WIRE 16 -1 (-3900 4475)(-3850 4475);
WIRE 16 -1 (-3850 4300)(-3850 4475);
WIRE 16 -1 (-3950 4475)(-3900 4475);
WIRE 16 -1 (-3900 4300)(-3900 4475);
WIRE 16 -1 (-4000 4475)(-3950 4475);
WIRE 16 -1 (-3950 4300)(-3950 4475);
WIRE 16 -1 (-4050 4475)(-4000 4475);
WIRE 16 -1 (-4000 4300)(-4000 4475);
WIRE 16 -1 (-4050 4300)(-4050 4475);
WIRE 16 -1 (-4100 4475)(-4050 4475);
WIRE 16 -1 (-4150 4475)(-4100 4475);
WIRE 16 -1 (-4100 4300)(-4100 4475);
WIRE 16 -1 (-4200 4475)(-4150 4475);
WIRE 16 -1 (-4150 4300)(-4150 4475);
WIRE 16 -1 (-4250 4475)(-4200 4475);
WIRE 16 -1 (-4200 4300)(-4200 4475);
WIRE 16 -1 (-4300 4475)(-4250 4475);
WIRE 16 -1 (-4250 4300)(-4250 4475);
WIRE 16 -1 (-4350 4475)(-4300 4475);
WIRE 16 -1 (-4300 4300)(-4300 4475);
WIRE 16 -1 (-4350 4300)(-4350 4475);
WIRE 16 -1 (-4400 4475)(-4350 4475);
WIRE 16 -1 (-4450 4475)(-4400 4475);
WIRE 16 -1 (-4400 4300)(-4400 4475);
WIRE 16 -1 (-4500 4475)(-4450 4475);
WIRE 16 -1 (-4450 4300)(-4450 4475);
WIRE 16 -1 (-4550 4475)(-4500 4475);
WIRE 16 -1 (-4500 4300)(-4500 4475);
WIRE 16 -1 (-4600 4475)(-4550 4475);
WIRE 16 -1 (-4550 4300)(-4550 4475);
WIRE 16 -1 (-4600 4300)(-4600 4475);
WIRE 16 -1 (-4650 4475)(-4600 4475);
WIRE 16 -1 (-4700 4475)(-4650 4475);
WIRE 16 -1 (-4650 4300)(-4650 4475);
WIRE 16 -1 (-4750 4475)(-4700 4475);
WIRE 16 -1 (-4700 4300)(-4700 4475);
WIRE 16 -1 (-4800 4475)(-4750 4475);
WIRE 16 -1 (-4750 4300)(-4750 4475);
WIRE 16 -1 (-4850 4475)(-4800 4475);
WIRE 16 -1 (-4800 4300)(-4800 4475);
WIRE 16 -1 (-4850 4300)(-4850 4475);
WIRE 16 -1 (-4900 4475)(-4850 4475);
WIRE 16 -1 (-4950 4475)(-4900 4475);
WIRE 16 -1 (-4900 4300)(-4900 4475);
WIRE 16 -1 (-5000 4475)(-4950 4475);
WIRE 16 -1 (-4950 4300)(-4950 4475);
WIRE 16 -1 (-5050 4475)(-5000 4475);
WIRE 16 -1 (-5000 4300)(-5000 4475);
WIRE 16 -1 (-5100 4475)(-5050 4475);
WIRE 16 -1 (-5050 4300)(-5050 4475);
WIRE 16 -1 (-5100 4300)(-5100 4475);
WIRE 16 -1 (-5150 4475)(-5100 4475);
WIRE 16 -1 (-5200 4475)(-5150 4475);
WIRE 16 -1 (-5150 4300)(-5150 4475);
WIRE 16 -1 (-5250 4475)(-5200 4475);
WIRE 16 -1 (-5200 4300)(-5200 4475);
WIRE 16 -1 (-5300 4475)(-5250 4475);
WIRE 16 -1 (-5250 4300)(-5250 4475);
WIRE 16 -1 (-5350 4475)(-5300 4475);
WIRE 16 -1 (-5300 4300)(-5300 4475);
WIRE 16 -1 (-5350 4300)(-5350 4475);
WIRE 16 -1 (-5400 4475)(-5350 4475);
WIRE 16 -1 (-5450 4475)(-5400 4475);
WIRE 16 -1 (-5400 4300)(-5400 4475);
WIRE 16 -1 (-5500 4475)(-5450 4475);
WIRE 16 -1 (-5450 4300)(-5450 4475);
WIRE 16 -1 (-5550 4475)(-5500 4475);
WIRE 16 -1 (-5500 4300)(-5500 4475);
WIRE 16 -1 (-5600 4475)(-5550 4475);
WIRE 16 -1 (-5550 4300)(-5550 4475);
WIRE 16 -1 (-5600 4300)(-5600 4475);
WIRE 16 -1 (-5650 4475)(-5600 4475);
WIRE 16 -1 (-5700 4475)(-5650 4475);
WIRE 16 -1 (-5650 4300)(-5650 4475);
WIRE 16 -1 (-5750 4475)(-5700 4475);
WIRE 16 -1 (-5700 4300)(-5700 4475);
WIRE 16 -1 (-5800 4475)(-5750 4475);
WIRE 16 -1 (-5750 4300)(-5750 4475);
WIRE 16 -1 (-5850 4475)(-5800 4475);
WIRE 16 -1 (-5800 4300)(-5800 4475);
WIRE 16 -1 (-5850 4300)(-5850 4475);
WIRE 16 -1 (-5900 4475)(-5850 4475);
WIRE 16 -1 (-5950 4475)(-5900 4475);
WIRE 16 -1 (-5900 4300)(-5900 4475);
WIRE 16 -1 (-6000 4475)(-5950 4475);
WIRE 16 -1 (-5950 4300)(-5950 4475);
WIRE 16 -1 (-6050 4475)(-6000 4475);
WIRE 16 -1 (-6000 4300)(-6000 4475);
WIRE 16 -1 (-6100 4475)(-6050 4475);
WIRE 16 -1 (-6050 4300)(-6050 4475);
WIRE 16 -1 (-6100 4300)(-6100 4475);
WIRE 16 -1 (-6150 4475)(-6100 4475);
WIRE 16 -1 (-6200 4475)(-6150 4475);
WIRE 16 -1 (-6150 4300)(-6150 4475);
WIRE 16 -1 (-6250 4475)(-6200 4475);
WIRE 16 -1 (-6200 4300)(-6200 4475);
WIRE 16 -1 (-6300 4475)(-6250 4475);
WIRE 16 -1 (-6250 4300)(-6250 4475);
WIRE 16 -1 (-6350 4475)(-6300 4475);
WIRE 16 -1 (-6300 4300)(-6300 4475);
WIRE 16 -1 (-6350 4300)(-6350 4475);
WIRE 16 -1 (-6400 4475)(-6350 4475);
WIRE 16 -1 (-6400 4300)(-6400 4475);
WIRE 16 -1 (-6450 4475)(-6400 4475);
WIRE 16 -1 (-6500 4475)(-6450 4475);
WIRE 16 -1 (-6450 4300)(-6450 4475);
WIRE 16 -1 (-6550 4475)(-6500 4475);
WIRE 16 -1 (-6500 4300)(-6500 4475);
WIRE 16 -1 (-6600 4475)(-6550 4475);
WIRE 16 -1 (-6550 4300)(-6550 4475);
WIRE 16 -1 (-6650 4475)(-6600 4475);
WIRE 16 -1 (-6600 4300)(-6600 4475);
WIRE 16 -1 (-6650 4300)(-6650 4475);
WIRE 16 -1 (-6700 4475)(-6650 4475);
WIRE 16 -1 (-6750 4475)(-6700 4475);
WIRE 16 -1 (-6700 4300)(-6700 4475);
WIRE 16 -1 (-6800 4475)(-6750 4475);
WIRE 16 -1 (-6750 4300)(-6750 4475);
WIRE 16 -1 (-6850 4475)(-6800 4475);
WIRE 16 -1 (-6800 4300)(-6800 4475);
WIRE 16 -1 (-6900 4475)(-6850 4475);
WIRE 16 -1 (-6850 4300)(-6850 4475);
WIRE 16 -1 (-6900 4300)(-6900 4475);
WIRE 16 -1 (-6950 4475)(-6900 4475);
WIRE 16 -1 (-7000 4475)(-6950 4475);
WIRE 16 -1 (-6950 4300)(-6950 4475);
WIRE 16 -1 (-7050 4475)(-7000 4475);
WIRE 16 -1 (-7000 4300)(-7000 4475);
WIRE 16 -1 (-7100 4475)(-7050 4475);
WIRE 16 -1 (-7050 4300)(-7050 4475);
WIRE 16 -1 (-7150 4475)(-7100 4475);
WIRE 16 -1 (-7100 4300)(-7100 4475);
WIRE 16 -1 (-7150 4300)(-7150 4475);
WIRE 16 -1 (-7200 4475)(-7150 4475);
WIRE 16 -1 (-7250 4475)(-7200 4475);
WIRE 16 -1 (-7200 4300)(-7200 4475);
WIRE 16 -1 (-7300 4475)(-7250 4475);
WIRE 16 -1 (-7250 4300)(-7250 4475);
WIRE 16 -1 (-7350 4475)(-7300 4475);
WIRE 16 -1 (-7300 4300)(-7300 4475);
WIRE 16 -1 (-7400 4475)(-7350 4475);
WIRE 16 -1 (-7350 4300)(-7350 4475);
WIRE 16 -1 (-7400 4300)(-7400 4475);
WIRE 16 -1 (-7450 4475)(-7400 4475);
WIRE 16 -1 (-7500 4475)(-7450 4475);
WIRE 16 -1 (-7450 4300)(-7450 4475);
WIRE 16 -1 (-7550 4475)(-7500 4475);
WIRE 16 -1 (-7500 4300)(-7500 4475);
WIRE 16 -1 (-7600 4475)(-7550 4475);
WIRE 16 -1 (-7550 4300)(-7550 4475);
WIRE 16 -1 (-7650 4475)(-7600 4475);
WIRE 16 -1 (-7600 4300)(-7600 4475);
WIRE 16 -1 (-7650 4300)(-7650 4475);
WIRE 16 -1 (-7700 4475)(-7650 4475);
WIRE 16 -1 (-7750 4475)(-7700 4475);
WIRE 16 -1 (-7700 4300)(-7700 4475);
WIRE 16 -1 (-7800 4475)(-7750 4475);
WIRE 16 -1 (-7750 4300)(-7750 4475);
WIRE 16 -1 (-7850 4475)(-7800 4475);
WIRE 16 -1 (-7800 4300)(-7800 4475);
WIRE 16 -1 (-7900 4475)(-7850 4475);
WIRE 16 -1 (-7850 4300)(-7850 4475);
WIRE 16 -1 (-7900 4300)(-7900 4475);
WIRE 16 -1 (-7950 4475)(-7900 4475);
WIRE 16 -1 (-8000 4475)(-7950 4475);
WIRE 16 -1 (-7950 4300)(-7950 4475);
WIRE 16 -1 (-8000 4300)(-8000 4475);
WIRE 16 -1 (-2100 3200)(-2100 3025);
WIRE 16 -1 (-1925 3025)(-2100 3025);
WIRE 16 -1 (-2100 3025)(-2150 3025);
WIRE 16 -1 (-2150 3200)(-2150 3025);
WIRE 16 -1 (-2200 3025)(-2150 3025);
WIRE 16 -1 (-2200 3200)(-2200 3025);
WIRE 16 -1 (-2250 3025)(-2200 3025);
WIRE 16 -1 (-2250 3200)(-2250 3025);
WIRE 16 -1 (-2300 3025)(-2250 3025);
WIRE 16 -1 (-2300 3200)(-2300 3025);
WIRE 16 -1 (-2350 3025)(-2300 3025);
WIRE 16 -1 (-2350 3200)(-2350 3025);
WIRE 16 -1 (-2400 3025)(-2350 3025);
WIRE 16 -1 (-2400 3025)(-2400 3200);
WIRE 16 -1 (-2450 3025)(-2400 3025);
WIRE 16 -1 (-2450 3025)(-2450 3200);
WIRE 16 -1 (-2500 3025)(-2450 3025);
WIRE 16 -1 (-2500 3200)(-2500 3025);
WIRE 16 -1 (-2550 3025)(-2500 3025);
WIRE 16 -1 (-2550 3025)(-2550 3200);
WIRE 16 -1 (-2600 3025)(-2550 3025);
WIRE 16 -1 (-2600 3025)(-2600 3200);
WIRE 16 -1 (-2650 3025)(-2600 3025);
WIRE 16 -1 (-2650 3200)(-2650 3025);
WIRE 16 -1 (-2700 3025)(-2650 3025);
WIRE 16 -1 (-2700 3025)(-2700 3200);
WIRE 16 -1 (-2750 3025)(-2700 3025);
WIRE 16 -1 (-2750 3200)(-2750 3025);
WIRE 16 -1 (-2800 3025)(-2750 3025);
WIRE 16 -1 (-2800 3025)(-2800 3200);
WIRE 16 -1 (-2850 3025)(-2800 3025);
WIRE 16 -1 (-2850 3025)(-2850 3200);
WIRE 16 -1 (-2900 3025)(-2850 3025);
WIRE 16 -1 (-2900 3200)(-2900 3025);
WIRE 16 -1 (-2950 3025)(-2900 3025);
WIRE 16 -1 (-2950 3025)(-2950 3200);
WIRE 16 -1 (-3000 3025)(-2950 3025);
WIRE 16 -1 (-3000 3200)(-3000 3025);
WIRE 16 -1 (-3050 3025)(-3000 3025);
WIRE 16 -1 (-3050 3025)(-3050 3200);
WIRE 16 -1 (-3100 3025)(-3050 3025);
WIRE 16 -1 (-3100 3025)(-3100 3200);
WIRE 16 -1 (-3150 3025)(-3100 3025);
WIRE 16 -1 (-3150 3200)(-3150 3025);
WIRE 16 -1 (-3200 3025)(-3150 3025);
WIRE 16 -1 (-3200 3025)(-3200 3200);
WIRE 16 -1 (-3250 3025)(-3200 3025);
WIRE 16 -1 (-3250 3200)(-3250 3025);
WIRE 16 -1 (-3300 3025)(-3250 3025);
WIRE 16 -1 (-3300 3025)(-3300 3200);
WIRE 16 -1 (-3350 3025)(-3300 3025);
WIRE 16 -1 (-3350 3025)(-3350 3200);
WIRE 16 -1 (-3400 3025)(-3350 3025);
WIRE 16 -1 (-3400 3200)(-3400 3025);
WIRE 16 -1 (-3450 3025)(-3400 3025);
WIRE 16 -1 (-3450 3025)(-3450 3200);
WIRE 16 -1 (-3500 3025)(-3450 3025);
WIRE 16 -1 (-3500 3200)(-3500 3025);
WIRE 16 -1 (-3550 3025)(-3500 3025);
WIRE 16 -1 (-3550 3200)(-3550 3025);
WIRE 16 -1 (-3600 3025)(-3550 3025);
WIRE 16 -1 (-3600 3025)(-3600 3200);
WIRE 16 -1 (-3650 3025)(-3600 3025);
WIRE 16 -1 (-3650 3200)(-3650 3025);
WIRE 16 -1 (-3700 3025)(-3650 3025);
WIRE 16 -1 (-3700 3025)(-3700 3200);
WIRE 16 -1 (-3750 3025)(-3700 3025);
WIRE 16 -1 (-3750 3025)(-3750 3200);
WIRE 16 -1 (-3800 3025)(-3750 3025);
WIRE 16 -1 (-3800 3200)(-3800 3025);
WIRE 16 -1 (-3850 3025)(-3800 3025);
WIRE 16 -1 (-3850 3025)(-3850 3200);
WIRE 16 -1 (-3900 3025)(-3850 3025);
WIRE 16 -1 (-3900 3200)(-3900 3025);
WIRE 16 -1 (-3950 3025)(-3900 3025);
WIRE 16 -1 (-3950 3025)(-3950 3200);
WIRE 16 -1 (-4000 3025)(-3950 3025);
WIRE 16 -1 (-4000 3025)(-4000 3200);
WIRE 16 -1 (-4050 3025)(-4000 3025);
WIRE 16 -1 (-4050 3200)(-4050 3025);
WIRE 16 -1 (-4100 3025)(-4050 3025);
WIRE 16 -1 (-4100 3025)(-4100 3200);
WIRE 16 -1 (-4150 3025)(-4100 3025);
WIRE 16 -1 (-4150 3200)(-4150 3025);
WIRE 16 -1 (-4200 3025)(-4150 3025);
WIRE 16 -1 (-4200 3025)(-4200 3200);
WIRE 16 -1 (-4250 3025)(-4200 3025);
WIRE 16 -1 (-4250 3025)(-4250 3200);
WIRE 16 -1 (-4300 3025)(-4250 3025);
WIRE 16 -1 (-4300 3200)(-4300 3025);
WIRE 16 -1 (-4350 3025)(-4300 3025);
WIRE 16 -1 (-4350 3025)(-4350 3200);
WIRE 16 -1 (-4400 3025)(-4350 3025);
WIRE 16 -1 (-4400 3200)(-4400 3025);
WIRE 16 -1 (-4450 3025)(-4400 3025);
WIRE 16 -1 (-4450 3025)(-4450 3200);
WIRE 16 -1 (-4500 3025)(-4450 3025);
WIRE 16 -1 (-4500 3025)(-4500 3200);
WIRE 16 -1 (-4550 3025)(-4500 3025);
WIRE 16 -1 (-4550 3200)(-4550 3025);
WIRE 16 -1 (-4600 3025)(-4550 3025);
WIRE 16 -1 (-4600 3025)(-4600 3200);
WIRE 16 -1 (-4650 3025)(-4600 3025);
WIRE 16 -1 (-4650 3025)(-4650 3200);
WIRE 16 -1 (-4700 3025)(-4650 3025);
WIRE 16 -1 (-4700 3200)(-4700 3025);
WIRE 16 -1 (-4750 3025)(-4700 3025);
WIRE 16 -1 (-4750 3025)(-4750 3200);
WIRE 16 -1 (-4800 3025)(-4750 3025);
WIRE 16 -1 (-4800 3200)(-4800 3025);
WIRE 16 -1 (-4850 3025)(-4800 3025);
WIRE 16 -1 (-4850 3025)(-4850 3200);
WIRE 16 -1 (-4900 3025)(-4850 3025);
WIRE 16 -1 (-4900 3025)(-4900 3200);
WIRE 16 -1 (-4950 3025)(-4900 3025);
WIRE 16 -1 (-4950 3200)(-4950 3025);
WIRE 16 -1 (-5000 3025)(-4950 3025);
WIRE 16 -1 (-5000 3025)(-5000 3200);
WIRE 16 -1 (-5050 3025)(-5000 3025);
WIRE 16 -1 (-5050 3200)(-5050 3025);
WIRE 16 -1 (-5100 3025)(-5050 3025);
WIRE 16 -1 (-5100 3025)(-5100 3200);
WIRE 16 -1 (-5150 3025)(-5100 3025);
WIRE 16 -1 (-5150 3025)(-5150 3200);
WIRE 16 -1 (-5200 3025)(-5150 3025);
WIRE 16 -1 (-5200 3200)(-5200 3025);
WIRE 16 -1 (-5250 3025)(-5200 3025);
WIRE 16 -1 (-5250 3025)(-5250 3200);
WIRE 16 -1 (-5300 3025)(-5250 3025);
WIRE 16 -1 (-5300 3200)(-5300 3025);
WIRE 16 -1 (-5350 3025)(-5300 3025);
WIRE 16 -1 (-5350 3025)(-5350 3200);
WIRE 16 -1 (-5400 3025)(-5350 3025);
WIRE 16 -1 (-5400 3025)(-5400 3200);
WIRE 16 -1 (-5450 3025)(-5400 3025);
WIRE 16 -1 (-5450 3200)(-5450 3025);
WIRE 16 -1 (-5500 3025)(-5450 3025);
WIRE 16 -1 (-5500 3025)(-5500 3200);
WIRE 16 -1 (-5550 3025)(-5500 3025);
WIRE 16 -1 (-5550 3200)(-5550 3025);
WIRE 16 -1 (-5600 3025)(-5550 3025);
WIRE 16 -1 (-5600 3025)(-5600 3200);
WIRE 16 -1 (-5650 3025)(-5600 3025);
WIRE 16 -1 (-5650 3025)(-5650 3200);
WIRE 16 -1 (-5700 3025)(-5650 3025);
WIRE 16 -1 (-5700 3200)(-5700 3025);
WIRE 16 -1 (-5750 3025)(-5700 3025);
WIRE 16 -1 (-5750 3025)(-5750 3200);
WIRE 16 -1 (-5800 3025)(-5750 3025);
WIRE 16 -1 (-5800 3025)(-5800 3200);
WIRE 16 -1 (-5850 3025)(-5800 3025);
WIRE 16 -1 (-5850 3200)(-5850 3025);
WIRE 16 -1 (-5900 3025)(-5850 3025);
WIRE 16 -1 (-5900 3025)(-5900 3200);
WIRE 16 -1 (-5950 3025)(-5900 3025);
WIRE 16 -1 (-5950 3200)(-5950 3025);
WIRE 16 -1 (-6000 3025)(-5950 3025);
WIRE 16 -1 (-6000 3025)(-6000 3200);
WIRE 16 -1 (-6050 3025)(-6000 3025);
WIRE 16 -1 (-6050 3025)(-6050 3200);
WIRE 16 -1 (-6100 3025)(-6050 3025);
WIRE 16 -1 (-6100 3200)(-6100 3025);
WIRE 16 -1 (-6150 3025)(-6100 3025);
WIRE 16 -1 (-6150 3025)(-6150 3200);
WIRE 16 -1 (-6200 3025)(-6150 3025);
WIRE 16 -1 (-6200 3200)(-6200 3025);
WIRE 16 -1 (-6250 3025)(-6200 3025);
WIRE 16 -1 (-6250 3025)(-6250 3200);
WIRE 16 -1 (-6300 3025)(-6250 3025);
WIRE 16 -1 (-6300 3025)(-6300 3200);
WIRE 16 -1 (-6350 3025)(-6300 3025);
WIRE 16 -1 (-6350 3200)(-6350 3025);
WIRE 16 -1 (-6400 3025)(-6350 3025);
WIRE 16 -1 (-6400 3025)(-6400 3200);
WIRE 16 -1 (-6450 3025)(-6400 3025);
WIRE 16 -1 (-6450 3200)(-6450 3025);
WIRE 16 -1 (-6500 3025)(-6450 3025);
WIRE 16 -1 (-6500 3025)(-6500 3200);
WIRE 16 -1 (-6550 3025)(-6500 3025);
WIRE 16 -1 (-6550 3025)(-6550 3200);
WIRE 16 -1 (-6600 3025)(-6550 3025);
WIRE 16 -1 (-6600 3200)(-6600 3025);
WIRE 16 -1 (-6650 3025)(-6600 3025);
WIRE 16 -1 (-6650 3025)(-6650 3200);
WIRE 16 -1 (-6700 3025)(-6650 3025);
WIRE 16 -1 (-6700 3200)(-6700 3025);
WIRE 16 -1 (-6750 3025)(-6700 3025);
WIRE 16 -1 (-6750 3200)(-6750 3025);
WIRE 16 -1 (-6800 3025)(-6750 3025);
WIRE 16 -1 (-6800 3025)(-6800 3200);
WIRE 16 -1 (-6850 3025)(-6800 3025);
WIRE 16 -1 (-6850 3200)(-6850 3025);
WIRE 16 -1 (-6900 3025)(-6850 3025);
WIRE 16 -1 (-6900 3025)(-6900 3200);
WIRE 16 -1 (-6950 3025)(-6900 3025);
WIRE 16 -1 (-6950 3025)(-6950 3200);
WIRE 16 -1 (-7000 3025)(-6950 3025);
WIRE 16 -1 (-7000 3200)(-7000 3025);
WIRE 16 -1 (-7050 3025)(-7000 3025);
WIRE 16 -1 (-7050 3025)(-7050 3200);
WIRE 16 -1 (-7100 3025)(-7050 3025);
WIRE 16 -1 (-7100 3200)(-7100 3025);
WIRE 16 -1 (-7150 3025)(-7100 3025);
WIRE 16 -1 (-7150 3025)(-7150 3200);
WIRE 16 -1 (-7200 3025)(-7150 3025);
WIRE 16 -1 (-7200 3025)(-7200 3200);
WIRE 16 -1 (-7250 3025)(-7200 3025);
WIRE 16 -1 (-7250 3200)(-7250 3025);
WIRE 16 -1 (-7300 3025)(-7250 3025);
WIRE 16 -1 (-7300 3025)(-7300 3200);
WIRE 16 -1 (-7350 3025)(-7300 3025);
WIRE 16 -1 (-7350 3200)(-7350 3025);
WIRE 16 -1 (-7400 3025)(-7350 3025);
WIRE 16 -1 (-7400 3025)(-7400 3200);
WIRE 16 -1 (-7450 3025)(-7400 3025);
WIRE 16 -1 (-7450 3025)(-7450 3200);
WIRE 16 -1 (-7500 3025)(-7450 3025);
WIRE 16 -1 (-7500 3200)(-7500 3025);
WIRE 16 -1 (-7550 3025)(-7500 3025);
WIRE 16 -1 (-7550 3025)(-7550 3200);
WIRE 16 -1 (-7600 3025)(-7550 3025);
WIRE 16 -1 (-7600 3200)(-7600 3025);
WIRE 16 -1 (-7650 3025)(-7600 3025);
WIRE 16 -1 (-7650 3025)(-7650 3200);
WIRE 16 -1 (-7700 3025)(-7650 3025);
WIRE 16 -1 (-7700 3025)(-7700 3200);
WIRE 16 -1 (-7750 3025)(-7700 3025);
WIRE 16 -1 (-7750 3200)(-7750 3025);
WIRE 16 -1 (-7800 3025)(-7750 3025);
WIRE 16 -1 (-7800 3025)(-7800 3200);
WIRE 16 -1 (-7850 3025)(-7800 3025);
WIRE 16 -1 (-7850 3025)(-7850 3200);
WIRE 16 -1 (-7900 3025)(-7850 3025);
WIRE 16 -1 (-7900 3200)(-7900 3025);
WIRE 16 -1 (-7950 3025)(-7900 3025);
WIRE 16 -1 (-7950 3025)(-7950 3200);
WIRE 16 -1 (-8000 3025)(-7950 3025);
WIRE 16 -1 (-8000 3200)(-8000 3025);
DOT 1 (-1600 4475);
DOT 1 (-1650 4475);
DOT 1 (-1700 4475);
DOT 1 (-1750 4475);
DOT 1 (-1800 4475);
DOT 1 (-1850 4475);
DOT 1 (-1900 4475);
DOT 1 (-1950 4475);
DOT 1 (-2000 4475);
DOT 1 (-2050 4475);
DOT 1 (-2100 4475);
DOT 1 (-2150 4475);
DOT 1 (-2200 4475);
DOT 1 (-2250 4475);
DOT 1 (-2300 4475);
DOT 1 (-2350 4475);
DOT 1 (-2400 4475);
DOT 1 (-2450 4475);
DOT 1 (-2500 4475);
DOT 1 (-2550 4475);
DOT 1 (-2600 4475);
DOT 1 (-2650 4475);
DOT 1 (-2700 4475);
DOT 1 (-2750 4475);
DOT 1 (-2800 4475);
DOT 1 (-2850 4475);
DOT 1 (-2900 4475);
DOT 1 (-2950 4475);
DOT 1 (-3050 4475);
DOT 1 (-3100 4475);
DOT 1 (-3150 4475);
DOT 1 (-3200 4475);
DOT 1 (-3250 4475);
DOT 1 (-3300 4475);
DOT 1 (-3350 4475);
DOT 1 (-3400 4475);
DOT 1 (-3450 4475);
DOT 1 (-3500 4475);
DOT 1 (-3550 4475);
DOT 1 (-3600 4475);
DOT 1 (-3650 4475);
DOT 1 (-3700 4475);
DOT 1 (-3750 4475);
DOT 1 (-3800 4475);
DOT 1 (-3850 4475);
DOT 1 (-3900 4475);
DOT 1 (-3950 4475);
DOT 1 (-4000 4475);
DOT 1 (-4050 4475);
DOT 1 (-4100 4475);
DOT 1 (-4150 4475);
DOT 1 (-4200 4475);
DOT 1 (-4250 4475);
DOT 1 (-4300 4475);
DOT 1 (-4350 4475);
DOT 1 (-4400 4475);
DOT 1 (-4450 4475);
DOT 1 (-4500 4475);
DOT 1 (-4550 4475);
DOT 1 (-4600 4475);
DOT 1 (-4650 4475);
DOT 1 (-4700 4475);
DOT 1 (-4750 4475);
DOT 1 (-4800 4475);
DOT 1 (-4850 4475);
DOT 1 (-4900 4475);
DOT 1 (-5000 4475);
DOT 1 (-5050 4475);
DOT 1 (-5100 4475);
DOT 1 (-5150 4475);
DOT 1 (-5200 4475);
DOT 1 (-5250 4475);
DOT 1 (-5350 4475);
DOT 1 (-5450 4475);
DOT 1 (-5500 4475);
DOT 1 (-5550 4475);
DOT 1 (-5600 4475);
DOT 1 (-5650 4475);
DOT 1 (-5700 4475);
DOT 1 (-5750 4475);
DOT 1 (-5800 4475);
DOT 1 (-5850 4475);
DOT 1 (-5900 4475);
DOT 1 (-5950 4475);
DOT 1 (-6000 4475);
DOT 1 (-6050 4475);
DOT 1 (-6100 4475);
DOT 1 (-6150 4475);
DOT 1 (-6200 4475);
DOT 1 (-6250 4475);
DOT 1 (-6300 4475);
DOT 1 (-6350 4475);
DOT 1 (-6400 4475);
DOT 1 (-6450 4475);
DOT 1 (-6500 4475);
DOT 1 (-6550 4475);
DOT 1 (-6600 4475);
DOT 1 (-6650 4475);
DOT 1 (-6700 4475);
DOT 1 (-6750 4475);
DOT 1 (-6800 4475);
DOT 1 (-6850 4475);
DOT 1 (-6900 4475);
DOT 1 (-6950 4475);
DOT 1 (-7000 4475);
DOT 1 (-7050 4475);
DOT 1 (-7100 4475);
DOT 1 (-7150 4475);
DOT 1 (-7200 4475);
DOT 1 (-7250 4475);
DOT 1 (-7300 4475);
DOT 1 (-7350 4475);
DOT 1 (-7400 4475);
DOT 1 (-7450 4475);
DOT 1 (-7500 4475);
DOT 1 (-7550 4475);
DOT 1 (-7600 4475);
DOT 1 (-7650 4475);
DOT 1 (-7700 4475);
DOT 1 (-7800 4475);
DOT 1 (-7850 4475);
DOT 1 (-7900 4475);
DOT 1 (-7950 4475);
DOT 1 (-2100 3025);
DOT 1 (-2150 3025);
DOT 1 (-2200 3025);
DOT 1 (-2250 3025);
DOT 1 (-2300 3025);
DOT 1 (-2350 3025);
DOT 1 (-2400 3025);
DOT 1 (-2450 3025);
DOT 1 (-2500 3025);
DOT 1 (-2550 3025);
DOT 1 (-2600 3025);
DOT 1 (-2650 3025);
DOT 1 (-2700 3025);
DOT 1 (-2750 3025);
DOT 1 (-2800 3025);
DOT 1 (-2850 3025);
DOT 1 (-2900 3025);
DOT 1 (-2950 3025);
DOT 1 (-3000 3025);
DOT 1 (-3050 3025);
DOT 1 (-3100 3025);
DOT 1 (-3200 3025);
DOT 1 (-3250 3025);
DOT 1 (-3300 3025);
DOT 1 (-3350 3025);
DOT 1 (-3400 3025);
DOT 1 (-3450 3025);
DOT 1 (-3500 3025);
DOT 1 (-3550 3025);
DOT 1 (-3600 3025);
DOT 1 (-3650 3025);
DOT 1 (-3700 3025);
DOT 1 (-3750 3025);
DOT 1 (-3900 3025);
DOT 1 (-3950 3025);
DOT 1 (-4000 3025);
DOT 1 (-4050 3025);
DOT 1 (-4100 3025);
DOT 1 (-4150 3025);
DOT 1 (-4200 3025);
DOT 1 (-4250 3025);
DOT 1 (-4300 3025);
DOT 1 (-4350 3025);
DOT 1 (-4400 3025);
DOT 1 (-4450 3025);
DOT 1 (-4550 3025);
DOT 1 (-4600 3025);
DOT 1 (-4650 3025);
DOT 1 (-4700 3025);
DOT 1 (-4750 3025);
DOT 1 (-4800 3025);
DOT 1 (-4850 3025);
DOT 1 (-4950 3025);
DOT 1 (-5000 3025);
DOT 1 (-5050 3025);
DOT 1 (-5100 3025);
DOT 1 (-5150 3025);
DOT 1 (-5200 3025);
DOT 1 (-5250 3025);
DOT 1 (-5300 3025);
DOT 1 (-5350 3025);
DOT 1 (-5400 3025);
DOT 1 (-5450 3025);
DOT 1 (-5500 3025);
DOT 1 (-5550 3025);
DOT 1 (-5600 3025);
DOT 1 (-5650 3025);
DOT 1 (-5700 3025);
DOT 1 (-5750 3025);
DOT 1 (-5800 3025);
DOT 1 (-5850 3025);
DOT 1 (-5900 3025);
DOT 1 (-5950 3025);
DOT 1 (-6000 3025);
DOT 1 (-6050 3025);
DOT 1 (-6100 3025);
DOT 1 (-6150 3025);
DOT 1 (-6200 3025);
DOT 1 (-6250 3025);
DOT 1 (-6300 3025);
DOT 1 (-6450 3025);
DOT 1 (-6500 3025);
DOT 1 (-6550 3025);
DOT 1 (-6600 3025);
DOT 1 (-6650 3025);
DOT 1 (-6700 3025);
DOT 1 (-6750 3025);
DOT 1 (-6800 3025);
DOT 1 (-6850 3025);
DOT 1 (-6900 3025);
DOT 1 (-6950 3025);
DOT 1 (-7000 3025);
DOT 1 (-7050 3025);
DOT 1 (-7100 3025);
DOT 1 (-7200 3025);
DOT 1 (-7250 3025);
DOT 1 (-7300 3025);
DOT 1 (-7350 3025);
DOT 1 (-7400 3025);
DOT 1 (-7450 3025);
DOT 1 (-7500 3025);
DOT 1 (-7550 3025);
DOT 1 (-7600 3025);
DOT 1 (-7650 3025);
DOT 1 (-7700 3025);
DOT 1 (-7750 3025);
DOT 1 (-7800 3025);
DOT 1 (-7850 3025);
DOT 1 (-7900 3025);
DOT 1 (-7950 3025);
DOT 1 (-4500 3025);
DOT 1 (-3800 3025);
DOT 1 (-3850 3025);
DOT 1 (-5400 4475);
DOT 1 (-5300 4475);
DOT 1 (-7150 3025);
DOT 1 (-7750 4475);
DOT 1 (-4900 3025);
DOT 1 (-6350 3025);
DOT 1 (-6400 3025);
DOT 1 (-4950 4475);
DOT 1 (-3000 4475);
DOT 1 (-3150 3025);
QUIT
